# T6G (Grand Teton) — schematic netlist excerpt (pin names and nets, part order shuffled) for the footprints in the layout excerpt that follows; sources: Cadence DE-HDL packaged netlist, KiCad conversion of 04192023_DAF0TMB3IC0_F0TG_MB_C_brd_V02_OCP.brd

C2602  Q_CAP  22UF 4V 20% X6S  pkg C0402  page 70 : A = PVDD11_S3_P0 ; B = GND
R233  Q_RES  0 5% CHIP  pkg 0402LF  page 82 : A = PWRGD_PVDDCR_CPU1_P0 ; B = FM_PWRGD_PVDDCR_CPU1_P0

(kicad_pcb
	(version 20260206)
	(generator "pcbnew")
	(generator_version "10.0")
	(general
		(thickness 1.6)
		(legacy_teardrops no)
	)
	(paper "A4")
	(title_block
		(title "04192023_DAF0TMB3IC0_F0TG_MB_C_brd_V02_OCP.brd")
		(comment 1 "Grand Teton / footprints 7645-7646 of 8354")
	)
	(layers
		(0 "F.Cu" signal "TOP")
		(4 "In1.Cu" signal "GND")
		(6 "In2.Cu" signal "IN1")
		(8 "In3.Cu" signal "GND1")
		(10 "In4.Cu" signal "IN2")
		(12 "In5.Cu" signal "GND2")
		(14 "In6.Cu" signal "IN3")
		(16 "In7.Cu" signal "GND3")
		(18 "In8.Cu" signal "VCC")
		(20 "In9.Cu" signal "VCC1")
		(22 "In10.Cu" signal "GND4")
		(24 "In11.Cu" signal "IN4")
		(26 "In12.Cu" signal "GND5")
		(28 "In13.Cu" signal "IN5")
		(30 "In14.Cu" signal "GND6")
		(32 "In15.Cu" signal "IN6")
		(34 "In16.Cu" signal "GND7")
		(2 "B.Cu" signal "BOTTOM")
		(9 "F.Adhes" user "F.Adhesive")
		(11 "B.Adhes" user "B.Adhesive")
		(13 "F.Paste" user "Package Geometry/Pastemask Top")
		(15 "B.Paste" user "Package Geometry/Pastemask Bottom")
		(5 "F.SilkS" user "Ref Des/Silkscreen Top")
		(7 "B.SilkS" user "Ref Des/Silkscreen Bottom")
		(1 "F.Mask" user "Board Geometry/Soldermask Top")
		(3 "B.Mask" user "Board Geometry/Soldermask Bottom")
		(17 "Dwgs.User" user "User.Drawings")
		(19 "Cmts.User" user "User.Comments")
		(21 "Eco1.User" user "User.Eco1")
		(23 "Eco2.User" user "User.Eco2")
		(25 "Edge.Cuts" user "Board Geometry/Outline")
		(27 "Margin" user)
		(31 "F.CrtYd" user "Package Geometry/Place Bound Top")
		(29 "B.CrtYd" user "Package Geometry/Place Bound Bottom")
		(35 "F.Fab" user "Ref Des/Assembly Top")
		(33 "B.Fab" user "Ref Des/Assembly Bottom")
	)
	(footprint ""
		(layer "B.Cu")
		(at 197.523608 -103.465376)
		(property "Reference" "R233"
			(at 0 0 0)
			(layer "B.SilkS")
			(hide yes)
			(effects
				(font
					(size 1.27 1.27)
				)
				(justify mirror)
			)
		)
		(property "Value" ""
			(at 0 0 0)
			(layer "B.Fab")
			(effects
				(font
					(size 1.27 1.27)
				)
				(justify mirror)
			)
		)
		(duplicate_pad_numbers_are_jumpers no)
		(fp_line
			(start -0.7874 -0.4064)
			(end -0.7874 0.4064)
			(stroke
				(width 0.1524)
				(type default)
			)
			(layer "B.SilkS")
		)
		(fp_line
			(start -0.7874 0.4064)
			(end 0.7874 0.4064)
			(stroke
				(width 0.1524)
				(type default)
			)
			(layer "B.SilkS")
		)
		(fp_line
			(start 0.7874 -0.4064)
			(end -0.7874 -0.4064)
			(stroke
				(width 0.1524)
				(type default)
			)
			(layer "B.SilkS")
		)
		(fp_line
			(start 0.7874 0.4064)
			(end 0.7874 -0.4064)
			(stroke
				(width 0.1524)
				(type default)
			)
			(layer "B.SilkS")
		)
		(fp_line
			(start -0.67945 -0.3048)
			(end -0.67945 0.3048)
			(stroke
				(width 0.1)
				(type default)
			)
			(layer "B.Fab")
		)
		(fp_line
			(start -0.67945 0.3048)
			(end -0.120396 0.3048)
			(stroke
				(width 0.1)
				(type default)
			)
			(layer "B.Fab")
		)
		(fp_line
			(start -0.12065 -0.3048)
			(end -0.67945 -0.3048)
			(stroke
				(width 0.1)
				(type default)
			)
			(layer "B.Fab")
		)
		(fp_line
			(start -0.12065 -0.2794)
			(end -0.12065 -0.3048)
			(stroke
				(width 0.1)
				(type default)
			)
			(layer "B.Fab")
		)
		(fp_line
			(start -0.120396 0.2794)
			(end 0.12065 0.2794)
			(stroke
				(width 0.1)
				(type default)
			)
			(layer "B.Fab")
		)
		(fp_line
			(start -0.120396 0.3048)
			(end -0.120396 0.2794)
			(stroke
				(width 0.1)
				(type default)
			)
			(layer "B.Fab")
		)
		(fp_line
			(start 0.12065 -0.305054)
			(end 0.12065 -0.2794)
			(stroke
				(width 0.1)
				(type default)
			)
			(layer "B.Fab")
		)
		(fp_line
			(start 0.12065 -0.2794)
			(end -0.12065 -0.2794)
			(stroke
				(width 0.1)
				(type default)
			)
			(layer "B.Fab")
		)
		(fp_line
			(start 0.12065 0.2794)
			(end 0.12065 0.3048)
			(stroke
				(width 0.1)
				(type default)
			)
			(layer "B.Fab")
		)
		(fp_line
			(start 0.12065 0.3048)
			(end 0.67945 0.3048)
			(stroke
				(width 0.1)
				(type default)
			)
			(layer "B.Fab")
		)
		(fp_line
			(start 0.67945 -0.305054)
			(end 0.12065 -0.305054)
			(stroke
				(width 0.1)
				(type default)
			)
			(layer "B.Fab")
		)
		(fp_line
			(start 0.67945 0.3048)
			(end 0.67945 -0.305054)
			(stroke
				(width 0.1)
				(type default)
			)
			(layer "B.Fab")
		)
		(pad "1" smd circle
			(at 0.40005 0 180)
			(size 0 0)
			(layers "B.Cu" "B.Mask" "B.Paste")
			(net "PWRGD_PVDDCR_CPU1_P0")
		)
		(pad "2" smd circle
			(at -0.40005 0 180)
			(size 0 0)
			(layers "B.Cu" "B.Mask" "B.Paste")
			(net "FM_PWRGD_PVDDCR_CPU1_P0")
		)
	)
	(footprint ""
		(layer "B.Cu")
		(at 354.406454 -264.35431)
		(property "Reference" "C2602"
			(at 0 0 0)
			(layer "B.SilkS")
			(hide yes)
			(effects
				(font
					(size 1.27 1.27)
				)
				(justify mirror)
			)
		)
		(property "Value" ""
			(at 0 0 0)
			(layer "B.Fab")
			(effects
				(font
					(size 1.27 1.27)
				)
				(justify mirror)
			)
		)
		(duplicate_pad_numbers_are_jumpers no)
		(fp_line
			(start -0.7874 -0.4064)
			(end -0.7874 0.4064)
			(stroke
				(width 0.1524)
				(type default)
			)
			(layer "B.SilkS")
		)
		(fp_line
			(start -0.7874 0.4064)
			(end 0.7874 0.4064)
			(stroke
				(width 0.1524)
				(type default)
			)
			(layer "B.SilkS")
		)
		(fp_line
			(start 0.7874 -0.4064)
			(end -0.7874 -0.4064)
			(stroke
				(width 0.1524)
				(type default)
			)
			(layer "B.SilkS")
		)
		(fp_line
			(start 0.7874 0.4064)
			(end 0.7874 -0.4064)
			(stroke
				(width 0.1524)
				(type default)
			)
			(layer "B.SilkS")
		)
		(fp_line
			(start -0.67945 -0.3048)
			(end -0.67945 0.3048)
			(stroke
				(width 0.1)
				(type default)
			)
			(layer "B.Fab")
		)
		(fp_line
			(start -0.67945 0.3048)
			(end -0.120396 0.3048)
			(stroke
				(width 0.1)
				(type default)
			)
			(layer "B.Fab")
		)
		(fp_line
			(start -0.12065 -0.3048)
			(end -0.67945 -0.3048)
			(stroke
				(width 0.1)
				(type default)
			)
			(layer "B.Fab")
		)
		(fp_line
			(start -0.12065 -0.2794)
			(end -0.12065 -0.3048)
			(stroke
				(width 0.1)
				(type default)
			)
			(layer "B.Fab")
		)
		(fp_line
			(start -0.120396 0.2794)
			(end 0.12065 0.2794)
			(stroke
				(width 0.1)
				(type default)
			)
			(layer "B.Fab")
		)
		(fp_line
			(start -0.120396 0.3048)
			(end -0.120396 0.2794)
			(stroke
				(width 0.1)
				(type default)
			)
			(layer "B.Fab")
		)
		(fp_line
			(start 0.12065 -0.305054)
			(end 0.12065 -0.2794)
			(stroke
				(width 0.1)
				(type default)
			)
			(layer "B.Fab")
		)
		(fp_line
			(start 0.12065 -0.2794)
			(end -0.12065 -0.2794)
			(stroke
				(width 0.1)
				(type default)
			)
			(layer "B.Fab")
		)
		(fp_line
			(start 0.12065 0.2794)
			(end 0.12065 0.3048)
			(stroke
				(width 0.1)
				(type default)
			)
			(layer "B.Fab")
		)
		(fp_line
			(start 0.12065 0.3048)
			(end 0.67945 0.3048)
			(stroke
				(width 0.1)
				(type default)
			)
			(layer "B.Fab")
		)
		(fp_line
			(start 0.67945 -0.305054)
			(end 0.12065 -0.305054)
			(stroke
				(width 0.1)
				(type default)
			)
			(layer "B.Fab")
		)
		(fp_line
			(start 0.67945 0.3048)
			(end 0.67945 -0.305054)
			(stroke
				(width 0.1)
				(type default)
			)
			(layer "B.Fab")
		)
		(pad "1" smd circle
			(at 0.40005 0 180)
			(size 0 0)
			(layers "B.Cu" "B.Mask" "B.Paste")
			(net "PVDD11_S3_P0")
		)
		(pad "2" smd circle
			(at -0.40005 0 180)
			(size 0 0)
			(layers "B.Cu" "B.Mask" "B.Paste")
			(net "GND")
		)
	)
)
